# BASEBOARD_FAB2 (Tioga Pass) — schematic netlist excerpt (pin names and nets, part order shuffled) for the footprints in the layout excerpt that follows; sources: Cadence DE-HDL packaged netlist, KiCad conversion of Wiwynn_Tioga_Pass_MB.brd

C5G51  CAP_A  22.0UF 4V 20% X6S  pkg 0603V  page 242 : A = PVDDQ_ABC ; B = GND
R3P18  RES  1.00K 1% CHIP  pkg 0402  page 211 : A = P3V3_STBY ; B = IRQ_PVCCIO_CPU0_VRHOT_N
R6P35  RES  100.0 1% EMPTY  pkg 0402  page 213 : A = PVCCIO_CPU1 ; B = SVID_DIO0_CPU1_R

(kicad_pcb
	(version 20260206)
	(generator "pcbnew")
	(generator_version "10.0")
	(general
		(thickness 1.6)
		(legacy_teardrops no)
	)
	(paper "A4")
	(title_block
		(title "Wiwynn_Tioga_Pass_MB.brd")
		(comment 1 "Tioga Pass / footprints 2926-2928 of 4770")
	)
	(layers
		(0 "F.Cu" signal "TOP")
		(4 "In1.Cu" signal "L2GND")
		(6 "In2.Cu" signal "L3")
		(8 "In3.Cu" signal "L4GND")
		(10 "In4.Cu" signal "L5")
		(12 "In5.Cu" signal "L6GND")
		(14 "In6.Cu" signal "L7VCC")
		(16 "In7.Cu" signal "L8VCC")
		(18 "In8.Cu" signal "L9GND")
		(20 "In9.Cu" signal "L10")
		(22 "In10.Cu" signal "L11GND")
		(24 "In11.Cu" signal "L12")
		(26 "In12.Cu" signal "L13GND")
		(2 "B.Cu" signal "BOTTOM")
		(9 "F.Adhes" user "F.Adhesive")
		(11 "B.Adhes" user "B.Adhesive")
		(13 "F.Paste" user "Package Geometry/Pastemask Top")
		(15 "B.Paste" user "Package Geometry/Pastemask Bottom")
		(5 "F.SilkS" user "Ref Des/Silkscreen Top")
		(7 "B.SilkS" user "Ref Des/Silkscreen Bottom")
		(1 "F.Mask" user "Board Geometry/Soldermask Top")
		(3 "B.Mask" user "Board Geometry/Soldermask Bottom")
		(17 "Dwgs.User" user "User.Drawings")
		(19 "Cmts.User" user "User.Comments")
		(21 "Eco1.User" user "User.Eco1")
		(23 "Eco2.User" user "User.Eco2")
		(25 "Edge.Cuts" user "Board Geometry/Outline")
		(27 "Margin" user)
		(31 "F.CrtYd" user "Package Geometry/Place Bound Top")
		(29 "B.CrtYd" user "Package Geometry/Place Bound Bottom")
		(35 "F.Fab" user "Ref Des/Assembly Top")
		(33 "B.Fab" user "Ref Des/Assembly Bottom")
	)
	(footprint ""
		(layer "B.Cu")
		(at 340.741 -84.5058 90)
		(property "Reference" "R3P18"
			(at 0 0 90)
			(layer "B.SilkS")
			(hide yes)
			(effects
				(font
					(size 1.27 1.27)
				)
				(justify mirror)
			)
		)
		(property "Value" ""
			(at 0 0 90)
			(layer "B.Fab")
			(effects
				(font
					(size 1.27 1.27)
				)
				(justify mirror)
			)
		)
		(duplicate_pad_numbers_are_jumpers no)
		(fp_poly
			(pts
				(xy 0.2794 -0.1016) (xy -0.2794 -0.1016) (xy -0.2794 0.9906) (xy 0.2794 0.9906)
			)
			(stroke
				(width 0)
				(type default)
			)
			(fill no)
			(layer "B.CrtYd")
		)
		(fp_line
			(start 0.2794 -0.1016)
			(end 0.2794 0.9906)
			(stroke
				(width 0.1)
				(type default)
			)
			(layer "B.Fab")
		)
		(fp_line
			(start -0.2794 -0.1016)
			(end 0.2794 -0.1016)
			(stroke
				(width 0.1)
				(type default)
			)
			(layer "B.Fab")
		)
		(fp_line
			(start 0.2794 0.9906)
			(end -0.2794 0.9906)
			(stroke
				(width 0.1)
				(type default)
			)
			(layer "B.Fab")
		)
		(fp_line
			(start -0.2794 0.9906)
			(end -0.2794 -0.1016)
			(stroke
				(width 0.1)
				(type default)
			)
			(layer "B.Fab")
		)
		(pad "1" smd rect
			(at 0 0 270)
			(size 0.508 0.508)
			(layers "B.Cu" "B.Mask" "B.Paste")
			(net "P3V3_STBY")
		)
		(pad "2" smd rect
			(at 0 0.889 270)
			(size 0.508 0.508)
			(layers "B.Cu" "B.Mask" "B.Paste")
			(net "IRQ_PVCCIO_CPU0_VRHOT_N")
		)
		(zone
			(layer "B.Cu")
			(hatch none 0.5)
			(connect_pads
				(clearance 0)
			)
			(min_thickness 0.25)
			(keepout
				(tracks allowed)
				(vias not_allowed)
				(pads allowed)
				(copperpour not_allowed)
				(footprints allowed)
			)
			(placement
				(enabled no)
				(sheetname "")
			)
			(fill
				(thermal_gap 0.5)
				(thermal_bridge_width 0.5)
				(island_removal_mode 0)
			)
			(polygon
				(pts
					(xy 340.995 -84.7598) (xy 340.995 -84.2518) (xy 341.376 -84.2518) (xy 341.376 -84.7598)
				)
			)
		)
		(zone
			(layer "B.Cu")
			(hatch none 0.5)
			(connect_pads
				(clearance 0)
			)
			(min_thickness 0.25)
			(keepout
				(tracks not_allowed)
				(vias allowed)
				(pads allowed)
				(copperpour not_allowed)
				(footprints allowed)
			)
			(placement
				(enabled no)
				(sheetname "")
			)
			(fill
				(thermal_gap 0.5)
				(thermal_bridge_width 0.5)
				(island_removal_mode 0)
			)
			(polygon
				(pts
					(xy 341.376 -84.7598) (xy 341.376 -84.2518) (xy 340.995 -84.2518) (xy 340.995 -84.7598)
				)
			)
		)
	)
	(footprint ""
		(layer "B.Cu")
		(at 164.973 -68.199 -90)
		(property "Reference" "R6P35"
			(at 0 0 90)
			(layer "B.SilkS")
			(hide yes)
			(effects
				(font
					(size 1.27 1.27)
				)
				(justify mirror)
			)
		)
		(property "Value" ""
			(at 0 0 90)
			(layer "B.Fab")
			(effects
				(font
					(size 1.27 1.27)
				)
				(justify mirror)
			)
		)
		(duplicate_pad_numbers_are_jumpers no)
		(fp_poly
			(pts
				(xy 0.2794 -0.1016) (xy -0.2794 -0.1016) (xy -0.2794 0.9906) (xy 0.2794 0.9906)
			)
			(stroke
				(width 0)
				(type default)
			)
			(fill no)
			(layer "B.CrtYd")
		)
		(fp_line
			(start -0.2794 0.9906)
			(end -0.2794 -0.1016)
			(stroke
				(width 0.1)
				(type default)
			)
			(layer "B.Fab")
		)
		(fp_line
			(start 0.2794 0.9906)
			(end -0.2794 0.9906)
			(stroke
				(width 0.1)
				(type default)
			)
			(layer "B.Fab")
		)
		(fp_line
			(start -0.2794 -0.1016)
			(end 0.2794 -0.1016)
			(stroke
				(width 0.1)
				(type default)
			)
			(layer "B.Fab")
		)
		(fp_line
			(start 0.2794 -0.1016)
			(end 0.2794 0.9906)
			(stroke
				(width 0.1)
				(type default)
			)
			(layer "B.Fab")
		)
		(pad "1" smd rect
			(at 0 0 90)
			(size 0.508 0.508)
			(layers "B.Cu" "B.Mask" "B.Paste")
			(net "PVCCIO_CPU1")
		)
		(pad "2" smd rect
			(at 0 0.889 90)
			(size 0.508 0.508)
			(layers "B.Cu" "B.Mask" "B.Paste")
			(net "SVID_DIO0_CPU1_R")
		)
		(zone
			(layer "B.Cu")
			(hatch none 0.5)
			(connect_pads
				(clearance 0)
			)
			(min_thickness 0.25)
			(keepout
				(tracks not_allowed)
				(vias allowed)
				(pads allowed)
				(copperpour not_allowed)
				(footprints allowed)
			)
			(placement
				(enabled no)
				(sheetname "")
			)
			(fill
				(thermal_gap 0.5)
				(thermal_bridge_width 0.5)
				(island_removal_mode 0)
			)
			(polygon
				(pts
					(xy 164.338 -67.945) (xy 164.338 -68.453) (xy 164.719 -68.453) (xy 164.719 -67.945)
				)
			)
		)
		(zone
			(layer "B.Cu")
			(hatch none 0.5)
			(connect_pads
				(clearance 0)
			)
			(min_thickness 0.25)
			(keepout
				(tracks allowed)
				(vias not_allowed)
				(pads allowed)
				(copperpour not_allowed)
				(footprints allowed)
			)
			(placement
				(enabled no)
				(sheetname "")
			)
			(fill
				(thermal_gap 0.5)
				(thermal_bridge_width 0.5)
				(island_removal_mode 0)
			)
			(polygon
				(pts
					(xy 164.719 -67.945) (xy 164.719 -68.453) (xy 164.338 -68.453) (xy 164.338 -67.945)
				)
			)
		)
	)
	(footprint ""
		(layer "B.Cu")
		(at 248.8565 -3.3528 -90)
		(property "Reference" "C5G51"
			(at -1.14681 0.76708 0)
			(unlocked yes)
			(layer "B.SilkS")
			(effects
				(font
					(size 0.7874 0.5842)
					(thickness 0.1524)
				)
				(justify mirror)
			)
		)
		(property "Value" ""
			(at 0 0 90)
			(layer "B.Fab")
			(effects
				(font
					(size 1.27 1.27)
				)
				(justify mirror)
			)
		)
		(duplicate_pad_numbers_are_jumpers no)
		(fp_rect
			(start 0.4953 1.6002)
			(end -0.4953 -0.2032)
			(stroke
				(width 0)
				(type default)
			)
			(fill no)
			(layer "B.CrtYd")
		)
		(fp_line
			(start -0.4953 1.6002)
			(end 0.4953 1.6002)
			(stroke
				(width 0.1)
				(type default)
			)
			(layer "B.Fab")
		)
		(fp_line
			(start 0.4953 1.6002)
			(end 0.4953 -0.2032)
			(stroke
				(width 0.1)
				(type default)
			)
			(layer "B.Fab")
		)
		(fp_line
			(start -0.4953 -0.2032)
			(end -0.4953 1.6002)
			(stroke
				(width 0.1)
				(type default)
			)
			(layer "B.Fab")
		)
		(fp_line
			(start 0.4953 -0.2032)
			(end -0.4953 -0.2032)
			(stroke
				(width 0.1)
				(type default)
			)
			(layer "B.Fab")
		)
		(pad "1" smd rect
			(at 0 0 90)
			(size 0.762 0.889)
			(layers "B.Cu" "B.Mask" "B.Paste")
			(net "PVDDQ_ABC")
		)
		(pad "2" smd rect
			(at 0 1.397 90)
			(size 0.762 0.889)
			(layers "B.Cu" "B.Mask" "B.Paste")
			(net "GND")
		)
		(zone
			(layer "B.Cu")
			(hatch none 0.5)
			(connect_pads
				(clearance 0)
			)
			(min_thickness 0.25)
			(keepout
				(tracks not_allowed)
				(vias allowed)
				(pads allowed)
				(copperpour not_allowed)
				(footprints allowed)
			)
			(placement
				(enabled no)
				(sheetname "")
			)
			(fill
				(thermal_gap 0.5)
				(thermal_bridge_width 0.5)
				(island_removal_mode 0)
			)
			(polygon
				(pts
					(xy 247.904 -2.9718) (xy 248.412 -2.9718) (xy 248.412 -3.7338) (xy 247.904 -3.7338)
				)
			)
		)
	)
)
